# BASEBOARD_FAB2 (Tioga Pass) — schematic netlist excerpt (pin names and nets, part order shuffled) for the footprints in the layout excerpt that follows; sources: Cadence DE-HDL packaged netlist, KiCad conversion of Wiwynn_Tioga_Pass_MB.brd

C5D32  CAP_A  22.0UF 4V 20% X6S  pkg 0603V  page 42 : A = PVCCIN_CPU0 ; B = GND
C5D46  CAP_A  22.0UF 4V 20% X6S  pkg 0603V  page 42 : A = PVCCIN_CPU0 ; B = GND
C5D10  CAP  10UF 4V 20% X6S  pkg 0603LF  page 42 : A = PVSA_CPU0 ; B = GND

(kicad_pcb
	(version 20260206)
	(generator "pcbnew")
	(generator_version "10.0")
	(general
		(thickness 1.6)
		(legacy_teardrops no)
	)
	(paper "A4")
	(title_block
		(title "Wiwynn_Tioga_Pass_MB.brd")
		(comment 1 "Tioga Pass / footprints 1460-1462 of 4770")
	)
	(layers
		(0 "F.Cu" signal "TOP")
		(4 "In1.Cu" signal "L2GND")
		(6 "In2.Cu" signal "L3")
		(8 "In3.Cu" signal "L4GND")
		(10 "In4.Cu" signal "L5")
		(12 "In5.Cu" signal "L6GND")
		(14 "In6.Cu" signal "L7VCC")
		(16 "In7.Cu" signal "L8VCC")
		(18 "In8.Cu" signal "L9GND")
		(20 "In9.Cu" signal "L10")
		(22 "In10.Cu" signal "L11GND")
		(24 "In11.Cu" signal "L12")
		(26 "In12.Cu" signal "L13GND")
		(2 "B.Cu" signal "BOTTOM")
		(9 "F.Adhes" user "F.Adhesive")
		(11 "B.Adhes" user "B.Adhesive")
		(13 "F.Paste" user "Package Geometry/Pastemask Top")
		(15 "B.Paste" user "Package Geometry/Pastemask Bottom")
		(5 "F.SilkS" user "Ref Des/Silkscreen Top")
		(7 "B.SilkS" user "Ref Des/Silkscreen Bottom")
		(1 "F.Mask" user "Board Geometry/Soldermask Top")
		(3 "B.Mask" user "Board Geometry/Soldermask Bottom")
		(17 "Dwgs.User" user "User.Drawings")
		(19 "Cmts.User" user "User.Comments")
		(21 "Eco1.User" user "User.Eco1")
		(23 "Eco2.User" user "User.Eco2")
		(25 "Edge.Cuts" user "Board Geometry/Outline")
		(27 "Margin" user)
		(31 "F.CrtYd" user "Package Geometry/Place Bound Top")
		(29 "B.CrtYd" user "Package Geometry/Place Bound Bottom")
		(35 "F.Fab" user "Ref Des/Assembly Top")
		(33 "B.Fab" user "Ref Des/Assembly Bottom")
	)
	(footprint ""
		(layer "F.Cu")
		(at 262.133334 -83.84159)
		(property "Reference" "C5D10"
			(at 0 0 0)
			(layer "F.SilkS")
			(hide yes)
			(effects
				(font
					(size 1.27 1.27)
				)
			)
		)
		(property "Value" ""
			(at 0 0 0)
			(layer "F.Fab")
			(effects
				(font
					(size 1.27 1.27)
				)
			)
		)
		(duplicate_pad_numbers_are_jumpers no)
		(fp_poly
			(pts
				(xy -0.4953 -0.2032) (xy 0.4953 -0.2032) (xy 0.4953 1.6002) (xy -0.4953 1.6002)
			)
			(stroke
				(width 0)
				(type default)
			)
			(fill no)
			(layer "F.CrtYd")
		)
		(fp_line
			(start -0.4953 -0.2032)
			(end 0.4953 -0.2032)
			(stroke
				(width 0.1)
				(type default)
			)
			(layer "F.Fab")
		)
		(fp_line
			(start -0.4953 1.6002)
			(end -0.4953 -0.2032)
			(stroke
				(width 0.1)
				(type default)
			)
			(layer "F.Fab")
		)
		(fp_line
			(start 0.4953 -0.2032)
			(end 0.4953 1.6002)
			(stroke
				(width 0.1)
				(type default)
			)
			(layer "F.Fab")
		)
		(fp_line
			(start 0.4953 1.6002)
			(end -0.4953 1.6002)
			(stroke
				(width 0.1)
				(type default)
			)
			(layer "F.Fab")
		)
		(pad "1" smd rect
			(at 0 0)
			(size 0.762 0.889)
			(layers "F.Cu" "F.Mask" "F.Paste")
			(net "PVSA_CPU0")
		)
		(pad "2" smd rect
			(at 0 1.397)
			(size 0.762 0.889)
			(layers "F.Cu" "F.Mask" "F.Paste")
			(net "GND")
		)
		(zone
			(layer "F.Cu")
			(hatch none 0.5)
			(connect_pads
				(clearance 0)
			)
			(min_thickness 0.25)
			(keepout
				(tracks not_allowed)
				(vias allowed)
				(pads allowed)
				(copperpour not_allowed)
				(footprints allowed)
			)
			(placement
				(enabled no)
				(sheetname "")
			)
			(fill
				(thermal_gap 0.5)
				(thermal_bridge_width 0.5)
				(island_removal_mode 0)
			)
			(polygon
				(pts
					(xy 261.752334 -83.39709) (xy 262.514334 -83.39709) (xy 262.514334 -82.88909) (xy 261.752334 -82.88909)
				)
			)
		)
	)
	(footprint ""
		(layer "F.Cu")
		(at 268.165072 -77.636116)
		(property "Reference" "C5D32"
			(at 0 0 0)
			(layer "F.SilkS")
			(hide yes)
			(effects
				(font
					(size 1.27 1.27)
				)
			)
		)
		(property "Value" ""
			(at 0 0 0)
			(layer "F.Fab")
			(effects
				(font
					(size 1.27 1.27)
				)
			)
		)
		(duplicate_pad_numbers_are_jumpers no)
		(fp_poly
			(pts
				(xy -0.4953 -0.2032) (xy 0.4953 -0.2032) (xy 0.4953 1.6002) (xy -0.4953 1.6002)
			)
			(stroke
				(width 0)
				(type default)
			)
			(fill no)
			(layer "F.CrtYd")
		)
		(fp_line
			(start -0.4953 -0.2032)
			(end 0.4953 -0.2032)
			(stroke
				(width 0.1)
				(type default)
			)
			(layer "F.Fab")
		)
		(fp_line
			(start -0.4953 1.6002)
			(end -0.4953 -0.2032)
			(stroke
				(width 0.1)
				(type default)
			)
			(layer "F.Fab")
		)
		(fp_line
			(start 0.4953 -0.2032)
			(end 0.4953 1.6002)
			(stroke
				(width 0.1)
				(type default)
			)
			(layer "F.Fab")
		)
		(fp_line
			(start 0.4953 1.6002)
			(end -0.4953 1.6002)
			(stroke
				(width 0.1)
				(type default)
			)
			(layer "F.Fab")
		)
		(pad "1" smd rect
			(at 0 0)
			(size 0.762 0.889)
			(layers "F.Cu" "F.Mask" "F.Paste")
			(net "PVCCIN_CPU0")
		)
		(pad "2" smd rect
			(at 0 1.397)
			(size 0.762 0.889)
			(layers "F.Cu" "F.Mask" "F.Paste")
			(net "GND")
		)
		(zone
			(layer "F.Cu")
			(hatch none 0.5)
			(connect_pads
				(clearance 0)
			)
			(min_thickness 0.25)
			(keepout
				(tracks not_allowed)
				(vias allowed)
				(pads allowed)
				(copperpour not_allowed)
				(footprints allowed)
			)
			(placement
				(enabled no)
				(sheetname "")
			)
			(fill
				(thermal_gap 0.5)
				(thermal_bridge_width 0.5)
				(island_removal_mode 0)
			)
			(polygon
				(pts
					(xy 267.784072 -77.191616) (xy 268.546072 -77.191616) (xy 268.546072 -76.683616) (xy 267.784072 -76.683616)
				)
			)
		)
	)
	(footprint ""
		(layer "F.Cu")
		(at 266.920472 -73.318116)
		(property "Reference" "C5D46"
			(at 0 0 0)
			(layer "F.SilkS")
			(hide yes)
			(effects
				(font
					(size 1.27 1.27)
				)
			)
		)
		(property "Value" ""
			(at 0 0 0)
			(layer "F.Fab")
			(effects
				(font
					(size 1.27 1.27)
				)
			)
		)
		(duplicate_pad_numbers_are_jumpers no)
		(fp_poly
			(pts
				(xy -0.4953 -0.2032) (xy 0.4953 -0.2032) (xy 0.4953 1.6002) (xy -0.4953 1.6002)
			)
			(stroke
				(width 0)
				(type default)
			)
			(fill no)
			(layer "F.CrtYd")
		)
		(fp_line
			(start -0.4953 -0.2032)
			(end 0.4953 -0.2032)
			(stroke
				(width 0.1)
				(type default)
			)
			(layer "F.Fab")
		)
		(fp_line
			(start -0.4953 1.6002)
			(end -0.4953 -0.2032)
			(stroke
				(width 0.1)
				(type default)
			)
			(layer "F.Fab")
		)
		(fp_line
			(start 0.4953 -0.2032)
			(end 0.4953 1.6002)
			(stroke
				(width 0.1)
				(type default)
			)
			(layer "F.Fab")
		)
		(fp_line
			(start 0.4953 1.6002)
			(end -0.4953 1.6002)
			(stroke
				(width 0.1)
				(type default)
			)
			(layer "F.Fab")
		)
		(pad "1" smd rect
			(at 0 0)
			(size 0.762 0.889)
			(layers "F.Cu" "F.Mask" "F.Paste")
			(net "PVCCIN_CPU0")
		)
		(pad "2" smd rect
			(at 0 1.397)
			(size 0.762 0.889)
			(layers "F.Cu" "F.Mask" "F.Paste")
			(net "GND")
		)
		(zone
			(layer "F.Cu")
			(hatch none 0.5)
			(connect_pads
				(clearance 0)
			)
			(min_thickness 0.25)
			(keepout
				(tracks not_allowed)
				(vias allowed)
				(pads allowed)
				(copperpour not_allowed)
				(footprints allowed)
			)
			(placement
				(enabled no)
				(sheetname "")
			)
			(fill
				(thermal_gap 0.5)
				(thermal_bridge_width 0.5)
				(island_removal_mode 0)
			)
			(polygon
				(pts
					(xy 266.539472 -72.873616) (xy 267.301472 -72.873616) (xy 267.301472 -72.365616) (xy 266.539472 -72.365616)
				)
			)
		)
	)
)
